(kicad_pcb
	(version 20260206)
	(generator "pcbnew")
	(generator_version "10.0")
	(general
		(thickness 1.6)
		(legacy_teardrops no)
	)
	(paper "A4")
	(title_block
		(title "03242023_DA0F0TMBIJ0_F0T_Motherboard_J_brd_V01_OCP.brd")
		(comment 1 "Grand Teton / footprints 3605-3610 of 6105")
	)
	(layers
		(0 "F.Cu" signal "TOP")
		(4 "In1.Cu" signal "GND")
		(6 "In2.Cu" signal "IN1")
		(8 "In3.Cu" signal "GND1")
		(10 "In4.Cu" signal "IN2")
		(12 "In5.Cu" signal "GND2")
		(14 "In6.Cu" signal "IN3")
		(16 "In7.Cu" signal "GND3")
		(18 "In8.Cu" signal "VCC")
		(20 "In9.Cu" signal "VCC1")
		(22 "In10.Cu" signal "GND4")
		(24 "In11.Cu" signal "IN4")
		(26 "In12.Cu" signal "GND5")
		(28 "In13.Cu" signal "IN5")
		(30 "In14.Cu" signal "GND6")
		(32 "In15.Cu" signal "IN6")
		(34 "In16.Cu" signal "GND7")
		(2 "B.Cu" signal "BOTTOM")
		(9 "F.Adhes" user "F.Adhesive")
		(11 "B.Adhes" user "B.Adhesive")
		(13 "F.Paste" user "Package Geometry/Pastemask Top")
		(15 "B.Paste" user "Package Geometry/Pastemask Bottom")
		(5 "F.SilkS" user "Ref Des/Silkscreen Top")
		(7 "B.SilkS" user "Ref Des/Silkscreen Bottom")
		(1 "F.Mask" user "Board Geometry/Soldermask Top")
		(3 "B.Mask" user "Board Geometry/Soldermask Bottom")
		(17 "Dwgs.User" user "User.Drawings")
		(19 "Cmts.User" user "User.Comments")
		(21 "Eco1.User" user "User.Eco1")
		(23 "Eco2.User" user "User.Eco2")
		(25 "Edge.Cuts" user "Board Geometry/Outline")
		(27 "Margin" user)
		(31 "F.CrtYd" user "Package Geometry/Place Bound Top")
		(29 "B.CrtYd" user "Package Geometry/Place Bound Bottom")
		(35 "F.Fab" user "Ref Des/Assembly Top")
		(33 "B.Fab" user "Ref Des/Assembly Bottom")
	)
	(footprint ""
		(layer "F.Cu")
		(at 315.110622 -54.219348 180)
		(property "Reference" "R624"
			(at 0 0 180)
			(layer "F.SilkS")
			(hide yes)
			(effects
				(font
					(size 1.27 1.27)
				)
			)
		)
		(property "Value" ""
			(at 0 0 180)
			(layer "F.Fab")
			(effects
				(font
					(size 1.27 1.27)
				)
			)
		)
		(duplicate_pad_numbers_are_jumpers no)
		(fp_line
			(start 0.7874 0.4064)
			(end -0.7874 0.4064)
			(stroke
				(width 0.1524)
				(type default)
			)
			(layer "F.SilkS")
		)
		(fp_line
			(start 0.7874 -0.4064)
			(end 0.7874 0.4064)
			(stroke
				(width 0.1524)
				(type default)
			)
			(layer "F.SilkS")
		)
		(fp_line
			(start -0.7874 0.4064)
			(end -0.7874 -0.4064)
			(stroke
				(width 0.1524)
				(type default)
			)
			(layer "F.SilkS")
		)
		(fp_line
			(start -0.7874 -0.4064)
			(end 0.7874 -0.4064)
			(stroke
				(width 0.1524)
				(type default)
			)
			(layer "F.SilkS")
		)
		(fp_line
			(start 0.67945 0.3048)
			(end 0.120396 0.3048)
			(stroke
				(width 0.1)
				(type default)
			)
			(layer "F.Fab")
		)
		(fp_line
			(start 0.67945 -0.3048)
			(end 0.67945 0.3048)
			(stroke
				(width 0.1)
				(type default)
			)
			(layer "F.Fab")
		)
		(fp_line
			(start 0.12065 -0.2794)
			(end 0.12065 -0.3048)
			(stroke
				(width 0.1)
				(type default)
			)
			(layer "F.Fab")
		)
		(fp_line
			(start 0.12065 -0.3048)
			(end 0.67945 -0.3048)
			(stroke
				(width 0.1)
				(type default)
			)
			(layer "F.Fab")
		)
		(fp_line
			(start 0.120396 0.3048)
			(end 0.120396 0.2794)
			(stroke
				(width 0.1)
				(type default)
			)
			(layer "F.Fab")
		)
		(fp_line
			(start 0.120396 0.2794)
			(end -0.12065 0.2794)
			(stroke
				(width 0.1)
				(type default)
			)
			(layer "F.Fab")
		)
		(fp_line
			(start -0.12065 0.3048)
			(end -0.67945 0.3048)
			(stroke
				(width 0.1)
				(type default)
			)
			(layer "F.Fab")
		)
		(fp_line
			(start -0.12065 0.2794)
			(end -0.12065 0.3048)
			(stroke
				(width 0.1)
				(type default)
			)
			(layer "F.Fab")
		)
		(fp_line
			(start -0.12065 -0.2794)
			(end 0.12065 -0.2794)
			(stroke
				(width 0.1)
				(type default)
			)
			(layer "F.Fab")
		)
		(fp_line
			(start -0.12065 -0.305054)
			(end -0.12065 -0.2794)
			(stroke
				(width 0.1)
				(type default)
			)
			(layer "F.Fab")
		)
		(fp_line
			(start -0.67945 0.3048)
			(end -0.67945 -0.305054)
			(stroke
				(width 0.1)
				(type default)
			)
			(layer "F.Fab")
		)
		(fp_line
			(start -0.67945 -0.305054)
			(end -0.12065 -0.305054)
			(stroke
				(width 0.1)
				(type default)
			)
			(layer "F.Fab")
		)
		(pad "1" smd circle
			(at -0.40005 0 180)
			(size 0 0)
			(layers "F.Cu" "F.Mask" "F.Paste")
			(net "FM_PCH_XTALSEL")
		)
		(pad "2" smd circle
			(at 0.40005 0 180)
			(size 0 0)
			(layers "F.Cu" "F.Mask" "F.Paste")
			(net "GND")
		)
	)
	(footprint ""
		(layer "F.Cu")
		(at 444.85814 -39.512748)
		(property "Reference" "U240"
			(at -2.3876 -2.250948 0)
			(unlocked yes)
			(layer "F.SilkS")
			(effects
				(font
					(size 0.7874 0.5842)
					(thickness 0.1524)
				)
				(justify left)
			)
		)
		(property "Value" ""
			(at 0 0 0)
			(layer "F.Fab")
			(effects
				(font
					(size 1.27 1.27)
				)
			)
		)
		(duplicate_pad_numbers_are_jumpers no)
		(fp_line
			(start -1.207008 -1.549908)
			(end -1.207008 1.549908)
			(stroke
				(width 0.1524)
				(type default)
			)
			(layer "F.SilkS")
		)
		(fp_line
			(start -1.207008 1.549908)
			(end 1.207008 1.549908)
			(stroke
				(width 0.1524)
				(type default)
			)
			(layer "F.SilkS")
		)
		(fp_line
			(start -0.762508 -1.549908)
			(end -1.207008 -1.549908)
			(stroke
				(width 0.1524)
				(type default)
			)
			(layer "F.SilkS")
		)
		(fp_line
			(start 0 -0.635)
			(end -0.762508 -1.549908)
			(stroke
				(width 0.1524)
				(type default)
			)
			(layer "F.SilkS")
		)
		(fp_line
			(start 0.762508 -1.549908)
			(end 0 -0.635)
			(stroke
				(width 0.1524)
				(type default)
			)
			(layer "F.SilkS")
		)
		(fp_line
			(start 1.207008 -1.549908)
			(end 0.762508 -1.549908)
			(stroke
				(width 0.1524)
				(type default)
			)
			(layer "F.SilkS")
		)
		(fp_line
			(start 1.207008 1.549908)
			(end 1.207008 -1.549908)
			(stroke
				(width 0.1524)
				(type default)
			)
			(layer "F.SilkS")
		)
		(fp_poly
			(pts
				(xy -3.4036 -1.53289) (xy -2.3876 -1.02489) (xy -3.4036 -0.51689)
			)
			(stroke
				(width 0)
				(type default)
			)
			(fill yes)
			(layer "F.SilkS")
		)
		(fp_line
			(start -1.549908 -1.549908)
			(end -1.549908 1.549908)
			(stroke
				(width 0.1)
				(type default)
			)
			(layer "F.Fab")
		)
		(fp_line
			(start -1.549908 1.549908)
			(end 1.549908 1.549908)
			(stroke
				(width 0.1)
				(type default)
			)
			(layer "F.Fab")
		)
		(fp_line
			(start 1.549908 -1.549908)
			(end -1.549908 -1.549908)
			(stroke
				(width 0.1)
				(type default)
			)
			(layer "F.Fab")
		)
		(fp_line
			(start 1.549908 1.549908)
			(end 1.549908 -1.549908)
			(stroke
				(width 0.1)
				(type default)
			)
			(layer "F.Fab")
		)
		(fp_poly
			(pts
				(xy -3.4036 -1.53289) (xy -3.4036 -0.51689) (xy -2.3876 -1.02489)
			)
			(stroke
				(width 0)
				(type default)
			)
			(fill yes)
			(layer "F.Fab")
		)
		(pad "1" smd rect
			(at -1.774952 -1.02489 270)
			(size 0.508 0.8636)
			(layers "F.Cu" "F.Mask" "F.Paste")
			(net "OCP_SFF_PRSNT0_R_N")
		)
		(pad "2" smd rect
			(at -1.774952 -0.32512 270)
			(size 0.4064 0.8636)
			(layers "F.Cu" "F.Mask" "F.Paste")
			(net "OCP_SFF_PRSNT1_R_N")
		)
		(pad "3" smd rect
			(at -1.774952 0.32512 270)
			(size 0.4064 0.8636)
			(layers "F.Cu" "F.Mask" "F.Paste")
			(net "OCP_SFF_PRSNT23_R_N")
		)
		(pad "4" smd rect
			(at -1.774952 1.02489 270)
			(size 0.508 0.8636)
			(layers "F.Cu" "F.Mask" "F.Paste")
			(net "GND")
		)
		(pad "5" smd rect
			(at 1.774952 1.02489 270)
			(size 0.508 0.8636)
			(layers "F.Cu" "F.Mask" "F.Paste")
			(net "OCP_SFF_PRSNT2_R_N")
		)
		(pad "6" smd rect
			(at 1.774952 0.32512 270)
			(size 0.4064 0.8636)
			(layers "F.Cu" "F.Mask" "F.Paste")
			(net "OCP_SFF_PRSNT3_R_N")
		)
		(pad "7" smd rect
			(at 1.774952 -0.32512 270)
			(size 0.4064 0.8636)
			(layers "F.Cu" "F.Mask" "F.Paste")
			(net "OCP_SFF_PRSNT01_R_N")
		)
		(pad "8" smd rect
			(at 1.774952 -1.02489 270)
			(size 0.508 0.8636)
			(layers "F.Cu" "F.Mask" "F.Paste")
			(net "P3V3_AUX")
		)
	)
	(footprint ""
		(layer "F.Cu")
		(at 435.185566 -41.1226 180)
		(property "Reference" "R1320"
			(at 0 0 180)
			(layer "F.SilkS")
			(hide yes)
			(effects
				(font
					(size 1.27 1.27)
				)
			)
		)
		(property "Value" ""
			(at 0 0 180)
			(layer "F.Fab")
			(effects
				(font
					(size 1.27 1.27)
				)
			)
		)
		(duplicate_pad_numbers_are_jumpers no)
		(fp_line
			(start 0.7874 0.4064)
			(end -0.7874 0.4064)
			(stroke
				(width 0.1524)
				(type default)
			)
			(layer "F.SilkS")
		)
		(fp_line
			(start 0.7874 -0.4064)
			(end 0.7874 0.4064)
			(stroke
				(width 0.1524)
				(type default)
			)
			(layer "F.SilkS")
		)
		(fp_line
			(start -0.7874 0.4064)
			(end -0.7874 -0.4064)
			(stroke
				(width 0.1524)
				(type default)
			)
			(layer "F.SilkS")
		)
		(fp_line
			(start -0.7874 -0.4064)
			(end 0.7874 -0.4064)
			(stroke
				(width 0.1524)
				(type default)
			)
			(layer "F.SilkS")
		)
		(fp_line
			(start 0.67945 0.3048)
			(end 0.120396 0.3048)
			(stroke
				(width 0.1)
				(type default)
			)
			(layer "F.Fab")
		)
		(fp_line
			(start 0.67945 -0.3048)
			(end 0.67945 0.3048)
			(stroke
				(width 0.1)
				(type default)
			)
			(layer "F.Fab")
		)
		(fp_line
			(start 0.12065 -0.2794)
			(end 0.12065 -0.3048)
			(stroke
				(width 0.1)
				(type default)
			)
			(layer "F.Fab")
		)
		(fp_line
			(start 0.12065 -0.3048)
			(end 0.67945 -0.3048)
			(stroke
				(width 0.1)
				(type default)
			)
			(layer "F.Fab")
		)
		(fp_line
			(start 0.120396 0.3048)
			(end 0.120396 0.2794)
			(stroke
				(width 0.1)
				(type default)
			)
			(layer "F.Fab")
		)
		(fp_line
			(start 0.120396 0.2794)
			(end -0.12065 0.2794)
			(stroke
				(width 0.1)
				(type default)
			)
			(layer "F.Fab")
		)
		(fp_line
			(start -0.12065 0.3048)
			(end -0.67945 0.3048)
			(stroke
				(width 0.1)
				(type default)
			)
			(layer "F.Fab")
		)
		(fp_line
			(start -0.12065 0.2794)
			(end -0.12065 0.3048)
			(stroke
				(width 0.1)
				(type default)
			)
			(layer "F.Fab")
		)
		(fp_line
			(start -0.12065 -0.2794)
			(end 0.12065 -0.2794)
			(stroke
				(width 0.1)
				(type default)
			)
			(layer "F.Fab")
		)
		(fp_line
			(start -0.12065 -0.305054)
			(end -0.12065 -0.2794)
			(stroke
				(width 0.1)
				(type default)
			)
			(layer "F.Fab")
		)
		(fp_line
			(start -0.67945 0.3048)
			(end -0.67945 -0.305054)
			(stroke
				(width 0.1)
				(type default)
			)
			(layer "F.Fab")
		)
		(fp_line
			(start -0.67945 -0.305054)
			(end -0.12065 -0.305054)
			(stroke
				(width 0.1)
				(type default)
			)
			(layer "F.Fab")
		)
		(pad "1" smd circle
			(at -0.40005 0 180)
			(size 0 0)
			(layers "F.Cu" "F.Mask" "F.Paste")
			(net "P3V3_AUX")
		)
		(pad "2" smd circle
			(at 0.40005 0 180)
			(size 0 0)
			(layers "F.Cu" "F.Mask" "F.Paste")
			(net "PU_SWAP_OVERRIDE_N")
		)
	)
	(footprint ""
		(layer "F.Cu")
		(at 192.877186 -438.17413 -90)
		(property "Reference" "R2940"
			(at 0 0 270)
			(layer "F.SilkS")
			(hide yes)
			(effects
				(font
					(size 1.27 1.27)
				)
			)
		)
		(property "Value" ""
			(at 0 0 270)
			(layer "F.Fab")
			(effects
				(font
					(size 1.27 1.27)
				)
			)
		)
		(duplicate_pad_numbers_are_jumpers no)
		(fp_line
			(start -0.7874 0.4064)
			(end -0.7874 -0.4064)
			(stroke
				(width 0.1524)
				(type default)
			)
			(layer "F.SilkS")
		)
		(fp_line
			(start 0.7874 0.4064)
			(end -0.7874 0.4064)
			(stroke
				(width 0.1524)
				(type default)
			)
			(layer "F.SilkS")
		)
		(fp_line
			(start -0.7874 -0.4064)
			(end 0.7874 -0.4064)
			(stroke
				(width 0.1524)
				(type default)
			)
			(layer "F.SilkS")
		)
		(fp_line
			(start 0.7874 -0.4064)
			(end 0.7874 0.4064)
			(stroke
				(width 0.1524)
				(type default)
			)
			(layer "F.SilkS")
		)
		(fp_line
			(start -0.67945 0.3048)
			(end -0.67945 -0.305054)
			(stroke
				(width 0.1)
				(type default)
			)
			(layer "F.Fab")
		)
		(fp_line
			(start -0.12065 0.3048)
			(end -0.67945 0.3048)
			(stroke
				(width 0.1)
				(type default)
			)
			(layer "F.Fab")
		)
		(fp_line
			(start 0.120396 0.3048)
			(end 0.120396 0.2794)
			(stroke
				(width 0.1)
				(type default)
			)
			(layer "F.Fab")
		)
		(fp_line
			(start 0.67945 0.3048)
			(end 0.120396 0.3048)
			(stroke
				(width 0.1)
				(type default)
			)
			(layer "F.Fab")
		)
		(fp_line
			(start -0.12065 0.2794)
			(end -0.12065 0.3048)
			(stroke
				(width 0.1)
				(type default)
			)
			(layer "F.Fab")
		)
		(fp_line
			(start 0.120396 0.2794)
			(end -0.12065 0.2794)
			(stroke
				(width 0.1)
				(type default)
			)
			(layer "F.Fab")
		)
		(fp_line
			(start -0.12065 -0.2794)
			(end 0.12065 -0.2794)
			(stroke
				(width 0.1)
				(type default)
			)
			(layer "F.Fab")
		)
		(fp_line
			(start 0.12065 -0.2794)
			(end 0.12065 -0.3048)
			(stroke
				(width 0.1)
				(type default)
			)
			(layer "F.Fab")
		)
		(fp_line
			(start 0.12065 -0.3048)
			(end 0.67945 -0.3048)
			(stroke
				(width 0.1)
				(type default)
			)
			(layer "F.Fab")
		)
		(fp_line
			(start 0.67945 -0.3048)
			(end 0.67945 0.3048)
			(stroke
				(width 0.1)
				(type default)
			)
			(layer "F.Fab")
		)
		(fp_line
			(start -0.67945 -0.305054)
			(end -0.12065 -0.305054)
			(stroke
				(width 0.1)
				(type default)
			)
			(layer "F.Fab")
		)
		(fp_line
			(start -0.12065 -0.305054)
			(end -0.12065 -0.2794)
			(stroke
				(width 0.1)
				(type default)
			)
			(layer "F.Fab")
		)
		(pad "1" smd circle
			(at -0.40005 0 270)
			(size 0 0)
			(layers "F.Cu" "F.Mask" "F.Paste")
			(net "P3V3_AUX")
		)
		(pad "2" smd circle
			(at 0.40005 0 270)
			(size 0 0)
			(layers "F.Cu" "F.Mask" "F.Paste")
			(net "FM_GPU_HSC_EN")
		)
	)
	(footprint ""
		(layer "F.Cu")
		(at 12.778232 -15.320518 90)
		(property "Reference" "R3177"
			(at 0 0 90)
			(layer "F.SilkS")
			(hide yes)
			(effects
				(font
					(size 1.27 1.27)
				)
			)
		)
		(property "Value" ""
			(at 0 0 90)
			(layer "F.Fab")
			(effects
				(font
					(size 1.27 1.27)
				)
			)
		)
		(duplicate_pad_numbers_are_jumpers no)
		(fp_line
			(start 0.7874 -0.4064)
			(end 0.7874 0.4064)
			(stroke
				(width 0.1524)
				(type default)
			)
			(layer "F.SilkS")
		)
		(fp_line
			(start -0.7874 -0.4064)
			(end 0.7874 -0.4064)
			(stroke
				(width 0.1524)
				(type default)
			)
			(layer "F.SilkS")
		)
		(fp_line
			(start 0.7874 0.4064)
			(end -0.7874 0.4064)
			(stroke
				(width 0.1524)
				(type default)
			)
			(layer "F.SilkS")
		)
		(fp_line
			(start -0.7874 0.4064)
			(end -0.7874 -0.4064)
			(stroke
				(width 0.1524)
				(type default)
			)
			(layer "F.SilkS")
		)
		(fp_line
			(start -0.12065 -0.305054)
			(end -0.12065 -0.2794)
			(stroke
				(width 0.1)
				(type default)
			)
			(layer "F.Fab")
		)
		(fp_line
			(start -0.67945 -0.305054)
			(end -0.12065 -0.305054)
			(stroke
				(width 0.1)
				(type default)
			)
			(layer "F.Fab")
		)
		(fp_line
			(start 0.67945 -0.3048)
			(end 0.67945 0.3048)
			(stroke
				(width 0.1)
				(type default)
			)
			(layer "F.Fab")
		)
		(fp_line
			(start 0.12065 -0.3048)
			(end 0.67945 -0.3048)
			(stroke
				(width 0.1)
				(type default)
			)
			(layer "F.Fab")
		)
		(fp_line
			(start 0.12065 -0.2794)
			(end 0.12065 -0.3048)
			(stroke
				(width 0.1)
				(type default)
			)
			(layer "F.Fab")
		)
		(fp_line
			(start -0.12065 -0.2794)
			(end 0.12065 -0.2794)
			(stroke
				(width 0.1)
				(type default)
			)
			(layer "F.Fab")
		)
		(fp_line
			(start 0.120396 0.2794)
			(end -0.12065 0.2794)
			(stroke
				(width 0.1)
				(type default)
			)
			(layer "F.Fab")
		)
		(fp_line
			(start -0.12065 0.2794)
			(end -0.12065 0.3048)
			(stroke
				(width 0.1)
				(type default)
			)
			(layer "F.Fab")
		)
		(fp_line
			(start 0.67945 0.3048)
			(end 0.120396 0.3048)
			(stroke
				(width 0.1)
				(type default)
			)
			(layer "F.Fab")
		)
		(fp_line
			(start 0.120396 0.3048)
			(end 0.120396 0.2794)
			(stroke
				(width 0.1)
				(type default)
			)
			(layer "F.Fab")
		)
		(fp_line
			(start -0.12065 0.3048)
			(end -0.67945 0.3048)
			(stroke
				(width 0.1)
				(type default)
			)
			(layer "F.Fab")
		)
		(fp_line
			(start -0.67945 0.3048)
			(end -0.67945 -0.305054)
			(stroke
				(width 0.1)
				(type default)
			)
			(layer "F.Fab")
		)
		(pad "1" smd circle
			(at -0.40005 0 90)
			(size 0 0)
			(layers "F.Cu" "F.Mask" "F.Paste")
			(net "USB2_5_R1_DN")
		)
		(pad "2" smd circle
			(at 0.40005 0 90)
			(size 0 0)
			(layers "F.Cu" "F.Mask" "F.Paste")
			(net "USB2_5_DN")
		)
	)
	(footprint ""
		(layer "F.Cu")
		(at 15.197582 -410.802836 90)
		(property "Reference" "R2922"
			(at 0 0 90)
			(layer "F.SilkS")
			(hide yes)
			(effects
				(font
					(size 1.27 1.27)
				)
			)
		)
		(property "Value" ""
			(at 0 0 90)
			(layer "F.Fab")
			(effects
				(font
					(size 1.27 1.27)
				)
			)
		)
		(duplicate_pad_numbers_are_jumpers no)
		(fp_line
			(start 0.7874 -0.4064)
			(end 0.7874 0.4064)
			(stroke
				(width 0.1524)
				(type default)
			)
			(layer "F.SilkS")
		)
		(fp_line
			(start -0.7874 -0.4064)
			(end 0.7874 -0.4064)
			(stroke
				(width 0.1524)
				(type default)
			)
			(layer "F.SilkS")
		)
		(fp_line
			(start 0.7874 0.4064)
			(end -0.7874 0.4064)
			(stroke
				(width 0.1524)
				(type default)
			)
			(layer "F.SilkS")
		)
		(fp_line
			(start -0.7874 0.4064)
			(end -0.7874 -0.4064)
			(stroke
				(width 0.1524)
				(type default)
			)
			(layer "F.SilkS")
		)
		(fp_line
			(start -0.12065 -0.305054)
			(end -0.12065 -0.2794)
			(stroke
				(width 0.1)
				(type default)
			)
			(layer "F.Fab")
		)
		(fp_line
			(start -0.67945 -0.305054)
			(end -0.12065 -0.305054)
			(stroke
				(width 0.1)
				(type default)
			)
			(layer "F.Fab")
		)
		(fp_line
			(start 0.67945 -0.3048)
			(end 0.67945 0.3048)
			(stroke
				(width 0.1)
				(type default)
			)
			(layer "F.Fab")
		)
		(fp_line
			(start 0.12065 -0.3048)
			(end 0.67945 -0.3048)
			(stroke
				(width 0.1)
				(type default)
			)
			(layer "F.Fab")
		)
		(fp_line
			(start 0.12065 -0.2794)
			(end 0.12065 -0.3048)
			(stroke
				(width 0.1)
				(type default)
			)
			(layer "F.Fab")
		)
		(fp_line
			(start -0.12065 -0.2794)
			(end 0.12065 -0.2794)
			(stroke
				(width 0.1)
				(type default)
			)
			(layer "F.Fab")
		)
		(fp_line
			(start 0.120396 0.2794)
			(end -0.12065 0.2794)
			(stroke
				(width 0.1)
				(type default)
			)
			(layer "F.Fab")
		)
		(fp_line
			(start -0.12065 0.2794)
			(end -0.12065 0.3048)
			(stroke
				(width 0.1)
				(type default)
			)
			(layer "F.Fab")
		)
		(fp_line
			(start 0.67945 0.3048)
			(end 0.120396 0.3048)
			(stroke
				(width 0.1)
				(type default)
			)
			(layer "F.Fab")
		)
		(fp_line
			(start 0.120396 0.3048)
			(end 0.120396 0.2794)
			(stroke
				(width 0.1)
				(type default)
			)
			(layer "F.Fab")
		)
		(fp_line
			(start -0.12065 0.3048)
			(end -0.67945 0.3048)
			(stroke
				(width 0.1)
				(type default)
			)
			(layer "F.Fab")
		)
		(fp_line
			(start -0.67945 0.3048)
			(end -0.67945 -0.305054)
			(stroke
				(width 0.1)
				(type default)
			)
			(layer "F.Fab")
		)
		(pad "1" smd circle
			(at -0.40005 0 90)
			(size 0 0)
			(layers "F.Cu" "F.Mask" "F.Paste")
			(net "RST_SMB_SWITCH_N")
		)
		(pad "2" smd circle
			(at 0.40005 0 90)
			(size 0 0)
			(layers "F.Cu" "F.Mask" "F.Paste")
			(net "PU_RST_SMB_U181_N")
		)
	)
)
